(kicad_pcb
	(version 20260206)
	(generator "pcbnew")
	(generator_version "10.0")
	(general
		(thickness 1.6)
		(legacy_teardrops no)
	)
	(paper "A4")
	(title_block
		(title "04192023_DAF0TMB3IC0_F0TG_MB_C_brd_V02_OCP.brd")
		(comment 1 "Grand Teton / footprints 173-179 of 8354")
	)
	(layers
		(0 "F.Cu" signal "TOP")
		(4 "In1.Cu" signal "GND")
		(6 "In2.Cu" signal "IN1")
		(8 "In3.Cu" signal "GND1")
		(10 "In4.Cu" signal "IN2")
		(12 "In5.Cu" signal "GND2")
		(14 "In6.Cu" signal "IN3")
		(16 "In7.Cu" signal "GND3")
		(18 "In8.Cu" signal "VCC")
		(20 "In9.Cu" signal "VCC1")
		(22 "In10.Cu" signal "GND4")
		(24 "In11.Cu" signal "IN4")
		(26 "In12.Cu" signal "GND5")
		(28 "In13.Cu" signal "IN5")
		(30 "In14.Cu" signal "GND6")
		(32 "In15.Cu" signal "IN6")
		(34 "In16.Cu" signal "GND7")
		(2 "B.Cu" signal "BOTTOM")
		(9 "F.Adhes" user "F.Adhesive")
		(11 "B.Adhes" user "B.Adhesive")
		(13 "F.Paste" user "Package Geometry/Pastemask Top")
		(15 "B.Paste" user "Package Geometry/Pastemask Bottom")
		(5 "F.SilkS" user "Ref Des/Silkscreen Top")
		(7 "B.SilkS" user "Ref Des/Silkscreen Bottom")
		(1 "F.Mask" user "Board Geometry/Soldermask Top")
		(3 "B.Mask" user "Board Geometry/Soldermask Bottom")
		(17 "Dwgs.User" user "User.Drawings")
		(19 "Cmts.User" user "User.Comments")
		(21 "Eco1.User" user "User.Eco1")
		(23 "Eco2.User" user "User.Eco2")
		(25 "Edge.Cuts" user "Board Geometry/Outline")
		(27 "Margin" user)
		(31 "F.CrtYd" user "Package Geometry/Place Bound Top")
		(29 "B.CrtYd" user "Package Geometry/Place Bound Bottom")
		(35 "F.Fab" user "Ref Des/Assembly Top")
		(33 "B.Fab" user "Ref Des/Assembly Bottom")
	)
	(footprint ""
		(layer "F.Cu")
		(at 184.023 -137.632948 -90)
		(property "Reference" "R1280"
			(at 0 0 270)
			(layer "F.SilkS")
			(hide yes)
			(effects
				(font
					(size 1.27 1.27)
				)
			)
		)
		(property "Value" ""
			(at 0 0 270)
			(layer "F.Fab")
			(effects
				(font
					(size 1.27 1.27)
				)
			)
		)
		(duplicate_pad_numbers_are_jumpers no)
		(fp_line
			(start -0.7874 0.4064)
			(end -0.7874 -0.4064)
			(stroke
				(width 0.1524)
				(type default)
			)
			(layer "F.SilkS")
		)
		(fp_line
			(start 0.7874 0.4064)
			(end -0.7874 0.4064)
			(stroke
				(width 0.1524)
				(type default)
			)
			(layer "F.SilkS")
		)
		(fp_line
			(start -0.7874 -0.4064)
			(end 0.7874 -0.4064)
			(stroke
				(width 0.1524)
				(type default)
			)
			(layer "F.SilkS")
		)
		(fp_line
			(start 0.7874 -0.4064)
			(end 0.7874 0.4064)
			(stroke
				(width 0.1524)
				(type default)
			)
			(layer "F.SilkS")
		)
		(fp_line
			(start -0.67945 0.3048)
			(end -0.67945 -0.305054)
			(stroke
				(width 0.1)
				(type default)
			)
			(layer "F.Fab")
		)
		(fp_line
			(start -0.12065 0.3048)
			(end -0.67945 0.3048)
			(stroke
				(width 0.1)
				(type default)
			)
			(layer "F.Fab")
		)
		(fp_line
			(start 0.120396 0.3048)
			(end 0.120396 0.2794)
			(stroke
				(width 0.1)
				(type default)
			)
			(layer "F.Fab")
		)
		(fp_line
			(start 0.67945 0.3048)
			(end 0.120396 0.3048)
			(stroke
				(width 0.1)
				(type default)
			)
			(layer "F.Fab")
		)
		(fp_line
			(start -0.12065 0.2794)
			(end -0.12065 0.3048)
			(stroke
				(width 0.1)
				(type default)
			)
			(layer "F.Fab")
		)
		(fp_line
			(start 0.120396 0.2794)
			(end -0.12065 0.2794)
			(stroke
				(width 0.1)
				(type default)
			)
			(layer "F.Fab")
		)
		(fp_line
			(start -0.12065 -0.2794)
			(end 0.12065 -0.2794)
			(stroke
				(width 0.1)
				(type default)
			)
			(layer "F.Fab")
		)
		(fp_line
			(start 0.12065 -0.2794)
			(end 0.12065 -0.3048)
			(stroke
				(width 0.1)
				(type default)
			)
			(layer "F.Fab")
		)
		(fp_line
			(start 0.12065 -0.3048)
			(end 0.67945 -0.3048)
			(stroke
				(width 0.1)
				(type default)
			)
			(layer "F.Fab")
		)
		(fp_line
			(start 0.67945 -0.3048)
			(end 0.67945 0.3048)
			(stroke
				(width 0.1)
				(type default)
			)
			(layer "F.Fab")
		)
		(fp_line
			(start -0.67945 -0.305054)
			(end -0.12065 -0.305054)
			(stroke
				(width 0.1)
				(type default)
			)
			(layer "F.Fab")
		)
		(fp_line
			(start -0.12065 -0.305054)
			(end -0.12065 -0.2794)
			(stroke
				(width 0.1)
				(type default)
			)
			(layer "F.Fab")
		)
		(pad "1" smd circle
			(at -0.40005 0 270)
			(size 0 0)
			(layers "F.Cu" "F.Mask" "F.Paste")
			(net "FM_P0_PCC0_N")
		)
		(pad "2" smd circle
			(at 0.40005 0 270)
			(size 0 0)
			(layers "F.Cu" "F.Mask" "F.Paste")
			(net "FM_P0_PCC0_R_N")
		)
	)
	(footprint ""
		(layer "F.Cu")
		(at 45.907706 19.444716 -90)
		(property "Reference" "JP6000_23"
			(at 0 0 270)
			(layer "F.SilkS")
			(hide yes)
			(effects
				(font
					(size 1.27 1.27)
				)
			)
		)
		(property "Value" ""
			(at 0 0 270)
			(layer "F.Fab")
			(effects
				(font
					(size 1.27 1.27)
				)
			)
		)
		(duplicate_pad_numbers_are_jumpers no)
		(pad "1" smd circle
			(at 0 0 270)
			(size 0.762 0.762)
			(layers "F.Cu" "F.Mask" "F.Paste")
			(net "Net_10792")
		)
	)
	(footprint ""
		(layer "F.Cu")
		(at 322.837048 -45.86351)
		(property "Reference" "R3866"
			(at 0 0 0)
			(layer "F.SilkS")
			(hide yes)
			(effects
				(font
					(size 1.27 1.27)
				)
			)
		)
		(property "Value" ""
			(at 0 0 0)
			(layer "F.Fab")
			(effects
				(font
					(size 1.27 1.27)
				)
			)
		)
		(duplicate_pad_numbers_are_jumpers no)
		(fp_line
			(start -0.7874 -0.4064)
			(end 0.7874 -0.4064)
			(stroke
				(width 0.1524)
				(type default)
			)
			(layer "F.SilkS")
		)
		(fp_line
			(start -0.7874 0.4064)
			(end -0.7874 -0.4064)
			(stroke
				(width 0.1524)
				(type default)
			)
			(layer "F.SilkS")
		)
		(fp_line
			(start 0.7874 -0.4064)
			(end 0.7874 0.4064)
			(stroke
				(width 0.1524)
				(type default)
			)
			(layer "F.SilkS")
		)
		(fp_line
			(start 0.7874 0.4064)
			(end -0.7874 0.4064)
			(stroke
				(width 0.1524)
				(type default)
			)
			(layer "F.SilkS")
		)
		(fp_line
			(start -0.67945 -0.305054)
			(end -0.12065 -0.305054)
			(stroke
				(width 0.1)
				(type default)
			)
			(layer "F.Fab")
		)
		(fp_line
			(start -0.67945 0.3048)
			(end -0.67945 -0.305054)
			(stroke
				(width 0.1)
				(type default)
			)
			(layer "F.Fab")
		)
		(fp_line
			(start -0.12065 -0.305054)
			(end -0.12065 -0.2794)
			(stroke
				(width 0.1)
				(type default)
			)
			(layer "F.Fab")
		)
		(fp_line
			(start -0.12065 -0.2794)
			(end 0.12065 -0.2794)
			(stroke
				(width 0.1)
				(type default)
			)
			(layer "F.Fab")
		)
		(fp_line
			(start -0.12065 0.2794)
			(end -0.12065 0.3048)
			(stroke
				(width 0.1)
				(type default)
			)
			(layer "F.Fab")
		)
		(fp_line
			(start -0.12065 0.3048)
			(end -0.67945 0.3048)
			(stroke
				(width 0.1)
				(type default)
			)
			(layer "F.Fab")
		)
		(fp_line
			(start 0.120396 0.2794)
			(end -0.12065 0.2794)
			(stroke
				(width 0.1)
				(type default)
			)
			(layer "F.Fab")
		)
		(fp_line
			(start 0.120396 0.3048)
			(end 0.120396 0.2794)
			(stroke
				(width 0.1)
				(type default)
			)
			(layer "F.Fab")
		)
		(fp_line
			(start 0.12065 -0.3048)
			(end 0.67945 -0.3048)
			(stroke
				(width 0.1)
				(type default)
			)
			(layer "F.Fab")
		)
		(fp_line
			(start 0.12065 -0.2794)
			(end 0.12065 -0.3048)
			(stroke
				(width 0.1)
				(type default)
			)
			(layer "F.Fab")
		)
		(fp_line
			(start 0.67945 -0.3048)
			(end 0.67945 0.3048)
			(stroke
				(width 0.1)
				(type default)
			)
			(layer "F.Fab")
		)
		(fp_line
			(start 0.67945 0.3048)
			(end 0.120396 0.3048)
			(stroke
				(width 0.1)
				(type default)
			)
			(layer "F.Fab")
		)
		(pad "1" smd rect
			(at -0.40005 0 180)
			(size 0.4572 0.508)
			(layers "F.Cu" "F.Mask" "F.Paste")
			(net "P12V_OCP_SFF_ISENSE_MPS_TIC")
		)
		(pad "2" smd rect
			(at 0.40005 0 180)
			(size 0.4572 0.508)
			(layers "F.Cu" "F.Mask" "F.Paste")
			(net "P12V_OCP_SFF_ISENSE_TIC")
		)
	)
	(footprint ""
		(layer "F.Cu")
		(at 413.770572 -159.116014 -90)
		(property "Reference" "PR366"
			(at 0 0 270)
			(layer "F.SilkS")
			(hide yes)
			(effects
				(font
					(size 1.27 1.27)
				)
			)
		)
		(property "Value" ""
			(at 0 0 270)
			(layer "F.Fab")
			(effects
				(font
					(size 1.27 1.27)
				)
			)
		)
		(duplicate_pad_numbers_are_jumpers no)
		(fp_line
			(start -0.7874 0.4064)
			(end -0.7874 -0.4064)
			(stroke
				(width 0.1524)
				(type default)
			)
			(layer "F.SilkS")
		)
		(fp_line
			(start 0.7874 0.4064)
			(end -0.7874 0.4064)
			(stroke
				(width 0.1524)
				(type default)
			)
			(layer "F.SilkS")
		)
		(fp_line
			(start -0.7874 -0.4064)
			(end 0.7874 -0.4064)
			(stroke
				(width 0.1524)
				(type default)
			)
			(layer "F.SilkS")
		)
		(fp_line
			(start 0.7874 -0.4064)
			(end 0.7874 0.4064)
			(stroke
				(width 0.1524)
				(type default)
			)
			(layer "F.SilkS")
		)
		(fp_line
			(start -0.67945 0.3048)
			(end -0.67945 -0.305054)
			(stroke
				(width 0.1)
				(type default)
			)
			(layer "F.Fab")
		)
		(fp_line
			(start -0.12065 0.3048)
			(end -0.67945 0.3048)
			(stroke
				(width 0.1)
				(type default)
			)
			(layer "F.Fab")
		)
		(fp_line
			(start 0.120396 0.3048)
			(end 0.120396 0.2794)
			(stroke
				(width 0.1)
				(type default)
			)
			(layer "F.Fab")
		)
		(fp_line
			(start 0.67945 0.3048)
			(end 0.120396 0.3048)
			(stroke
				(width 0.1)
				(type default)
			)
			(layer "F.Fab")
		)
		(fp_line
			(start -0.12065 0.2794)
			(end -0.12065 0.3048)
			(stroke
				(width 0.1)
				(type default)
			)
			(layer "F.Fab")
		)
		(fp_line
			(start 0.120396 0.2794)
			(end -0.12065 0.2794)
			(stroke
				(width 0.1)
				(type default)
			)
			(layer "F.Fab")
		)
		(fp_line
			(start -0.12065 -0.2794)
			(end 0.12065 -0.2794)
			(stroke
				(width 0.1)
				(type default)
			)
			(layer "F.Fab")
		)
		(fp_line
			(start 0.12065 -0.2794)
			(end 0.12065 -0.3048)
			(stroke
				(width 0.1)
				(type default)
			)
			(layer "F.Fab")
		)
		(fp_line
			(start 0.12065 -0.3048)
			(end 0.67945 -0.3048)
			(stroke
				(width 0.1)
				(type default)
			)
			(layer "F.Fab")
		)
		(fp_line
			(start 0.67945 -0.3048)
			(end 0.67945 0.3048)
			(stroke
				(width 0.1)
				(type default)
			)
			(layer "F.Fab")
		)
		(fp_line
			(start -0.67945 -0.305054)
			(end -0.12065 -0.305054)
			(stroke
				(width 0.1)
				(type default)
			)
			(layer "F.Fab")
		)
		(fp_line
			(start -0.12065 -0.305054)
			(end -0.12065 -0.2794)
			(stroke
				(width 0.1)
				(type default)
			)
			(layer "F.Fab")
		)
		(pad "1" smd circle
			(at -0.40005 0 270)
			(size 0 0)
			(layers "F.Cu" "F.Mask" "F.Paste")
			(net "SW_PVDDCR_SOC_P0_BOOT3")
		)
		(pad "2" smd circle
			(at 0.40005 0 270)
			(size 0 0)
			(layers "F.Cu" "F.Mask" "F.Paste")
			(net "SW_PVDDCR_SOC_P0_BOOT3_RC")
		)
	)
	(footprint ""
		(layer "F.Cu")
		(at 224.21215 -47.612046)
		(property "Reference" "R10287"
			(at 0 0 0)
			(layer "F.SilkS")
			(hide yes)
			(effects
				(font
					(size 1.27 1.27)
				)
			)
		)
		(property "Value" ""
			(at 0 0 0)
			(layer "F.Fab")
			(effects
				(font
					(size 1.27 1.27)
				)
			)
		)
		(duplicate_pad_numbers_are_jumpers no)
		(fp_line
			(start -0.7874 -0.4064)
			(end 0.7874 -0.4064)
			(stroke
				(width 0.1524)
				(type default)
			)
			(layer "F.SilkS")
		)
		(fp_line
			(start -0.7874 0.4064)
			(end -0.7874 -0.4064)
			(stroke
				(width 0.1524)
				(type default)
			)
			(layer "F.SilkS")
		)
		(fp_line
			(start 0.7874 -0.4064)
			(end 0.7874 0.4064)
			(stroke
				(width 0.1524)
				(type default)
			)
			(layer "F.SilkS")
		)
		(fp_line
			(start 0.7874 0.4064)
			(end -0.7874 0.4064)
			(stroke
				(width 0.1524)
				(type default)
			)
			(layer "F.SilkS")
		)
		(fp_line
			(start -0.67945 -0.305054)
			(end -0.12065 -0.305054)
			(stroke
				(width 0.1)
				(type default)
			)
			(layer "F.Fab")
		)
		(fp_line
			(start -0.67945 0.3048)
			(end -0.67945 -0.305054)
			(stroke
				(width 0.1)
				(type default)
			)
			(layer "F.Fab")
		)
		(fp_line
			(start -0.12065 -0.305054)
			(end -0.12065 -0.2794)
			(stroke
				(width 0.1)
				(type default)
			)
			(layer "F.Fab")
		)
		(fp_line
			(start -0.12065 -0.2794)
			(end 0.12065 -0.2794)
			(stroke
				(width 0.1)
				(type default)
			)
			(layer "F.Fab")
		)
		(fp_line
			(start -0.12065 0.2794)
			(end -0.12065 0.3048)
			(stroke
				(width 0.1)
				(type default)
			)
			(layer "F.Fab")
		)
		(fp_line
			(start -0.12065 0.3048)
			(end -0.67945 0.3048)
			(stroke
				(width 0.1)
				(type default)
			)
			(layer "F.Fab")
		)
		(fp_line
			(start 0.120396 0.2794)
			(end -0.12065 0.2794)
			(stroke
				(width 0.1)
				(type default)
			)
			(layer "F.Fab")
		)
		(fp_line
			(start 0.120396 0.3048)
			(end 0.120396 0.2794)
			(stroke
				(width 0.1)
				(type default)
			)
			(layer "F.Fab")
		)
		(fp_line
			(start 0.12065 -0.3048)
			(end 0.67945 -0.3048)
			(stroke
				(width 0.1)
				(type default)
			)
			(layer "F.Fab")
		)
		(fp_line
			(start 0.12065 -0.2794)
			(end 0.12065 -0.3048)
			(stroke
				(width 0.1)
				(type default)
			)
			(layer "F.Fab")
		)
		(fp_line
			(start 0.67945 -0.3048)
			(end 0.67945 0.3048)
			(stroke
				(width 0.1)
				(type default)
			)
			(layer "F.Fab")
		)
		(fp_line
			(start 0.67945 0.3048)
			(end 0.120396 0.3048)
			(stroke
				(width 0.1)
				(type default)
			)
			(layer "F.Fab")
		)
		(pad "1" smd circle
			(at -0.40005 0)
			(size 0 0)
			(layers "F.Cu" "F.Mask" "F.Paste")
			(net "P3V3_E1S_0")
		)
		(pad "2" smd circle
			(at 0.40005 0)
			(size 0 0)
			(layers "F.Cu" "F.Mask" "F.Paste")
			(net "E1S_0_PERST1_CLKREQ_N")
		)
	)
	(footprint ""
		(layer "F.Cu")
		(at 27.686 -434.9623 180)
		(property "Reference" "R2899"
			(at 0 0 180)
			(layer "F.SilkS")
			(hide yes)
			(effects
				(font
					(size 1.27 1.27)
				)
			)
		)
		(property "Value" ""
			(at 0 0 180)
			(layer "F.Fab")
			(effects
				(font
					(size 1.27 1.27)
				)
			)
		)
		(duplicate_pad_numbers_are_jumpers no)
		(fp_line
			(start 0.7874 0.4064)
			(end -0.7874 0.4064)
			(stroke
				(width 0.1524)
				(type default)
			)
			(layer "F.SilkS")
		)
		(fp_line
			(start 0.7874 -0.4064)
			(end 0.7874 0.4064)
			(stroke
				(width 0.1524)
				(type default)
			)
			(layer "F.SilkS")
		)
		(fp_line
			(start -0.7874 0.4064)
			(end -0.7874 -0.4064)
			(stroke
				(width 0.1524)
				(type default)
			)
			(layer "F.SilkS")
		)
		(fp_line
			(start -0.7874 -0.4064)
			(end 0.7874 -0.4064)
			(stroke
				(width 0.1524)
				(type default)
			)
			(layer "F.SilkS")
		)
		(fp_line
			(start 0.67945 0.3048)
			(end 0.120396 0.3048)
			(stroke
				(width 0.1)
				(type default)
			)
			(layer "F.Fab")
		)
		(fp_line
			(start 0.67945 -0.3048)
			(end 0.67945 0.3048)
			(stroke
				(width 0.1)
				(type default)
			)
			(layer "F.Fab")
		)
		(fp_line
			(start 0.12065 -0.2794)
			(end 0.12065 -0.3048)
			(stroke
				(width 0.1)
				(type default)
			)
			(layer "F.Fab")
		)
		(fp_line
			(start 0.12065 -0.3048)
			(end 0.67945 -0.3048)
			(stroke
				(width 0.1)
				(type default)
			)
			(layer "F.Fab")
		)
		(fp_line
			(start 0.120396 0.3048)
			(end 0.120396 0.2794)
			(stroke
				(width 0.1)
				(type default)
			)
			(layer "F.Fab")
		)
		(fp_line
			(start 0.120396 0.2794)
			(end -0.12065 0.2794)
			(stroke
				(width 0.1)
				(type default)
			)
			(layer "F.Fab")
		)
		(fp_line
			(start -0.12065 0.3048)
			(end -0.67945 0.3048)
			(stroke
				(width 0.1)
				(type default)
			)
			(layer "F.Fab")
		)
		(fp_line
			(start -0.12065 0.2794)
			(end -0.12065 0.3048)
			(stroke
				(width 0.1)
				(type default)
			)
			(layer "F.Fab")
		)
		(fp_line
			(start -0.12065 -0.2794)
			(end 0.12065 -0.2794)
			(stroke
				(width 0.1)
				(type default)
			)
			(layer "F.Fab")
		)
		(fp_line
			(start -0.12065 -0.305054)
			(end -0.12065 -0.2794)
			(stroke
				(width 0.1)
				(type default)
			)
			(layer "F.Fab")
		)
		(fp_line
			(start -0.67945 0.3048)
			(end -0.67945 -0.305054)
			(stroke
				(width 0.1)
				(type default)
			)
			(layer "F.Fab")
		)
		(fp_line
			(start -0.67945 -0.305054)
			(end -0.12065 -0.305054)
			(stroke
				(width 0.1)
				(type default)
			)
			(layer "F.Fab")
		)
		(pad "1" smd circle
			(at -0.40005 0 180)
			(size 0 0)
			(layers "F.Cu" "F.Mask" "F.Paste")
			(net "SMB_BMC_GPU_EN")
		)
		(pad "2" smd circle
			(at 0.40005 0 180)
			(size 0 0)
			(layers "F.Cu" "F.Mask" "F.Paste")
			(net "SMB_BMC_GPU_EN_R1")
		)
	)
	(footprint ""
		(layer "F.Cu")
		(at 436.613046 -351.22866 -90)
		(property "Reference" "PC208_2"
			(at 0 0 270)
			(layer "F.SilkS")
			(hide yes)
			(effects
				(font
					(size 1.27 1.27)
				)
			)
		)
		(property "Value" ""
			(at 0 0 270)
			(layer "F.Fab")
			(effects
				(font
					(size 1.27 1.27)
				)
			)
		)
		(duplicate_pad_numbers_are_jumpers no)
		(fp_line
			(start -0.7874 0.4064)
			(end -0.7874 -0.4064)
			(stroke
				(width 0.1524)
				(type default)
			)
			(layer "F.SilkS")
		)
		(fp_line
			(start 0.7874 0.4064)
			(end -0.7874 0.4064)
			(stroke
				(width 0.1524)
				(type default)
			)
			(layer "F.SilkS")
		)
		(fp_line
			(start -0.7874 -0.4064)
			(end 0.7874 -0.4064)
			(stroke
				(width 0.1524)
				(type default)
			)
			(layer "F.SilkS")
		)
		(fp_line
			(start 0.7874 -0.4064)
			(end 0.7874 0.4064)
			(stroke
				(width 0.1524)
				(type default)
			)
			(layer "F.SilkS")
		)
		(fp_line
			(start -0.67945 0.3048)
			(end -0.67945 -0.305054)
			(stroke
				(width 0.1)
				(type default)
			)
			(layer "F.Fab")
		)
		(fp_line
			(start -0.12065 0.3048)
			(end -0.67945 0.3048)
			(stroke
				(width 0.1)
				(type default)
			)
			(layer "F.Fab")
		)
		(fp_line
			(start 0.120396 0.3048)
			(end 0.120396 0.2794)
			(stroke
				(width 0.1)
				(type default)
			)
			(layer "F.Fab")
		)
		(fp_line
			(start 0.67945 0.3048)
			(end 0.120396 0.3048)
			(stroke
				(width 0.1)
				(type default)
			)
			(layer "F.Fab")
		)
		(fp_line
			(start -0.12065 0.2794)
			(end -0.12065 0.3048)
			(stroke
				(width 0.1)
				(type default)
			)
			(layer "F.Fab")
		)
		(fp_line
			(start 0.120396 0.2794)
			(end -0.12065 0.2794)
			(stroke
				(width 0.1)
				(type default)
			)
			(layer "F.Fab")
		)
		(fp_line
			(start -0.12065 -0.2794)
			(end 0.12065 -0.2794)
			(stroke
				(width 0.1)
				(type default)
			)
			(layer "F.Fab")
		)
		(fp_line
			(start 0.12065 -0.2794)
			(end 0.12065 -0.3048)
			(stroke
				(width 0.1)
				(type default)
			)
			(layer "F.Fab")
		)
		(fp_line
			(start 0.12065 -0.3048)
			(end 0.67945 -0.3048)
			(stroke
				(width 0.1)
				(type default)
			)
			(layer "F.Fab")
		)
		(fp_line
			(start 0.67945 -0.3048)
			(end 0.67945 0.3048)
			(stroke
				(width 0.1)
				(type default)
			)
			(layer "F.Fab")
		)
		(fp_line
			(start -0.67945 -0.305054)
			(end -0.12065 -0.305054)
			(stroke
				(width 0.1)
				(type default)
			)
			(layer "F.Fab")
		)
		(fp_line
			(start -0.12065 -0.305054)
			(end -0.12065 -0.2794)
			(stroke
				(width 0.1)
				(type default)
			)
			(layer "F.Fab")
		)
		(pad "1" smd circle
			(at -0.40005 0 270)
			(size 0 0)
			(layers "F.Cu" "F.Mask" "F.Paste")
			(net "SW_P12V_AUX_PVDD11_S3_P0_FLT")
		)
		(pad "2" smd circle
			(at 0.40005 0 270)
			(size 0 0)
			(layers "F.Cu" "F.Mask" "F.Paste")
			(net "GND")
		)
	)
)
